# S9S_MB_2U (Grand Teton) — schematic netlist excerpt (pin names and nets, part order shuffled) for the footprints in the layout excerpt that follows; sources: Cadence DE-HDL packaged netlist, KiCad conversion of 03242023_DA0F0TMBIJ0_F0T_Motherboard_J_brd_V01_OCP.brd

PC233_P0_7  Q_CAP  1UF 16V 10% X6S  pkg C0402  page 270 : A = SW_P12V_PVCCIN_CPU0_FLT ; B = GND
C1574  Q_CAP_DIFFBUS  DIFF BUS_0.22UF 6.3V 20% X6S  pkg C0201  page 175 : \1\ = P5E_CPU0_PE4_TX_C_DN<2> ; \2\ = P5E_CPU0_PE4_TX_DN<2>
C1526  Q_CAP_DIFFBUS  DIFF BUS_0.22UF 6.3V 20% X6S  pkg C0201  page 177 : \1\ = P5E_CPU1_PE3_TX_C_DN<10> ; \2\ = P5E_CPU1_PE3_TX_DN<10>

(kicad_pcb
	(version 20260206)
	(generator "pcbnew")
	(generator_version "10.0")
	(general
		(thickness 1.6)
		(legacy_teardrops no)
	)
	(paper "A4")
	(title_block
		(title "03242023_DA0F0TMBIJ0_F0T_Motherboard_J_brd_V01_OCP.brd")
		(comment 1 "Grand Teton / footprints 678-680 of 6105")
	)
	(layers
		(0 "F.Cu" signal "TOP")
		(4 "In1.Cu" signal "GND")
		(6 "In2.Cu" signal "IN1")
		(8 "In3.Cu" signal "GND1")
		(10 "In4.Cu" signal "IN2")
		(12 "In5.Cu" signal "GND2")
		(14 "In6.Cu" signal "IN3")
		(16 "In7.Cu" signal "GND3")
		(18 "In8.Cu" signal "VCC")
		(20 "In9.Cu" signal "VCC1")
		(22 "In10.Cu" signal "GND4")
		(24 "In11.Cu" signal "IN4")
		(26 "In12.Cu" signal "GND5")
		(28 "In13.Cu" signal "IN5")
		(30 "In14.Cu" signal "GND6")
		(32 "In15.Cu" signal "IN6")
		(34 "In16.Cu" signal "GND7")
		(2 "B.Cu" signal "BOTTOM")
		(9 "F.Adhes" user "F.Adhesive")
		(11 "B.Adhes" user "B.Adhesive")
		(13 "F.Paste" user "Package Geometry/Pastemask Top")
		(15 "B.Paste" user "Package Geometry/Pastemask Bottom")
		(5 "F.SilkS" user "Ref Des/Silkscreen Top")
		(7 "B.SilkS" user "Ref Des/Silkscreen Bottom")
		(1 "F.Mask" user "Board Geometry/Soldermask Top")
		(3 "B.Mask" user "Board Geometry/Soldermask Bottom")
		(17 "Dwgs.User" user "User.Drawings")
		(19 "Cmts.User" user "User.Comments")
		(21 "Eco1.User" user "User.Eco1")
		(23 "Eco2.User" user "User.Eco2")
		(25 "Edge.Cuts" user "Board Geometry/Outline")
		(27 "Margin" user)
		(31 "F.CrtYd" user "Package Geometry/Place Bound Top")
		(29 "B.CrtYd" user "Package Geometry/Place Bound Bottom")
		(35 "F.Fab" user "Ref Des/Assembly Top")
		(33 "B.Fab" user "Ref Des/Assembly Bottom")
	)
	(footprint ""
		(layer "F.Cu")
		(at 136.791954 -408.517344 -90)
		(property "Reference" "C1526"
			(at 0 0 270)
			(layer "F.SilkS")
			(hide yes)
			(effects
				(font
					(size 1.27 1.27)
				)
			)
		)
		(property "Value" ""
			(at 0 0 270)
			(layer "F.Fab")
			(effects
				(font
					(size 1.27 1.27)
				)
			)
		)
		(duplicate_pad_numbers_are_jumpers no)
		(fp_line
			(start -0.299974 0.150114)
			(end -0.299974 -0.150114)
			(stroke
				(width 0.1)
				(type default)
			)
			(layer "F.Fab")
		)
		(fp_line
			(start 0.299974 0.150114)
			(end -0.299974 0.150114)
			(stroke
				(width 0.1)
				(type default)
			)
			(layer "F.Fab")
		)
		(fp_line
			(start -0.299974 -0.150114)
			(end 0.299974 -0.150114)
			(stroke
				(width 0.1)
				(type default)
			)
			(layer "F.Fab")
		)
		(fp_line
			(start 0.299974 -0.150114)
			(end 0.299974 0.150114)
			(stroke
				(width 0.1)
				(type default)
			)
			(layer "F.Fab")
		)
		(pad "1" smd rect
			(at -0.2667 0 270)
			(size 0.3048 0.381)
			(layers "F.Cu" "F.Mask" "F.Paste")
			(net "P5E_CPU1_PE3_TX_C_DN<10>")
		)
		(pad "2" smd rect
			(at 0.2667 0 270)
			(size 0.3048 0.381)
			(layers "F.Cu" "F.Mask" "F.Paste")
			(net "P5E_CPU1_PE3_TX_DN<10>")
		)
	)
	(footprint ""
		(layer "F.Cu")
		(at 310.081168 -402.371052 -90)
		(property "Reference" "C1574"
			(at 0 0 270)
			(layer "F.SilkS")
			(hide yes)
			(effects
				(font
					(size 1.27 1.27)
				)
			)
		)
		(property "Value" ""
			(at 0 0 270)
			(layer "F.Fab")
			(effects
				(font
					(size 1.27 1.27)
				)
			)
		)
		(duplicate_pad_numbers_are_jumpers no)
		(fp_line
			(start -0.299974 0.150114)
			(end -0.299974 -0.150114)
			(stroke
				(width 0.1)
				(type default)
			)
			(layer "F.Fab")
		)
		(fp_line
			(start 0.299974 0.150114)
			(end -0.299974 0.150114)
			(stroke
				(width 0.1)
				(type default)
			)
			(layer "F.Fab")
		)
		(fp_line
			(start -0.299974 -0.150114)
			(end 0.299974 -0.150114)
			(stroke
				(width 0.1)
				(type default)
			)
			(layer "F.Fab")
		)
		(fp_line
			(start 0.299974 -0.150114)
			(end 0.299974 0.150114)
			(stroke
				(width 0.1)
				(type default)
			)
			(layer "F.Fab")
		)
		(pad "1" smd rect
			(at -0.2667 0 270)
			(size 0.3048 0.381)
			(layers "F.Cu" "F.Mask" "F.Paste")
			(net "P5E_CPU0_PE4_TX_C_DN<2>")
		)
		(pad "2" smd rect
			(at 0.2667 0 270)
			(size 0.3048 0.381)
			(layers "F.Cu" "F.Mask" "F.Paste")
			(net "P5E_CPU0_PE4_TX_DN<2>")
		)
	)
	(footprint ""
		(layer "F.Cu")
		(at 332.26756 -343.005156 -90)
		(property "Reference" "PC233_P0_7"
			(at 0 0 270)
			(layer "F.SilkS")
			(hide yes)
			(effects
				(font
					(size 1.27 1.27)
				)
			)
		)
		(property "Value" ""
			(at 0 0 270)
			(layer "F.Fab")
			(effects
				(font
					(size 1.27 1.27)
				)
			)
		)
		(duplicate_pad_numbers_are_jumpers no)
		(fp_line
			(start -0.7874 0.4064)
			(end -0.7874 -0.4064)
			(stroke
				(width 0.1524)
				(type default)
			)
			(layer "F.SilkS")
		)
		(fp_line
			(start 0.7874 0.4064)
			(end -0.7874 0.4064)
			(stroke
				(width 0.1524)
				(type default)
			)
			(layer "F.SilkS")
		)
		(fp_line
			(start -0.7874 -0.4064)
			(end 0.7874 -0.4064)
			(stroke
				(width 0.1524)
				(type default)
			)
			(layer "F.SilkS")
		)
		(fp_line
			(start 0.7874 -0.4064)
			(end 0.7874 0.4064)
			(stroke
				(width 0.1524)
				(type default)
			)
			(layer "F.SilkS")
		)
		(fp_line
			(start -0.67945 0.3048)
			(end -0.67945 -0.305054)
			(stroke
				(width 0.1)
				(type default)
			)
			(layer "F.Fab")
		)
		(fp_line
			(start -0.12065 0.3048)
			(end -0.67945 0.3048)
			(stroke
				(width 0.1)
				(type default)
			)
			(layer "F.Fab")
		)
		(fp_line
			(start 0.120396 0.3048)
			(end 0.120396 0.2794)
			(stroke
				(width 0.1)
				(type default)
			)
			(layer "F.Fab")
		)
		(fp_line
			(start 0.67945 0.3048)
			(end 0.120396 0.3048)
			(stroke
				(width 0.1)
				(type default)
			)
			(layer "F.Fab")
		)
		(fp_line
			(start -0.12065 0.2794)
			(end -0.12065 0.3048)
			(stroke
				(width 0.1)
				(type default)
			)
			(layer "F.Fab")
		)
		(fp_line
			(start 0.120396 0.2794)
			(end -0.12065 0.2794)
			(stroke
				(width 0.1)
				(type default)
			)
			(layer "F.Fab")
		)
		(fp_line
			(start -0.12065 -0.2794)
			(end 0.12065 -0.2794)
			(stroke
				(width 0.1)
				(type default)
			)
			(layer "F.Fab")
		)
		(fp_line
			(start 0.12065 -0.2794)
			(end 0.12065 -0.3048)
			(stroke
				(width 0.1)
				(type default)
			)
			(layer "F.Fab")
		)
		(fp_line
			(start 0.12065 -0.3048)
			(end 0.67945 -0.3048)
			(stroke
				(width 0.1)
				(type default)
			)
			(layer "F.Fab")
		)
		(fp_line
			(start 0.67945 -0.3048)
			(end 0.67945 0.3048)
			(stroke
				(width 0.1)
				(type default)
			)
			(layer "F.Fab")
		)
		(fp_line
			(start -0.67945 -0.305054)
			(end -0.12065 -0.305054)
			(stroke
				(width 0.1)
				(type default)
			)
			(layer "F.Fab")
		)
		(fp_line
			(start -0.12065 -0.305054)
			(end -0.12065 -0.2794)
			(stroke
				(width 0.1)
				(type default)
			)
			(layer "F.Fab")
		)
		(pad "1" smd circle
			(at -0.40005 0 270)
			(size 0 0)
			(layers "F.Cu" "F.Mask" "F.Paste")
			(net "SW_P12V_PVCCIN_CPU0_FLT")
		)
		(pad "2" smd circle
			(at 0.40005 0 270)
			(size 0 0)
			(layers "F.Cu" "F.Mask" "F.Paste")
			(net "GND")
		)
	)
)
